(kicad_pcb
	(version 20260206)
	(generator "pcbnew")
	(generator_version "10.0")
	(general
		(thickness 1.6)
		(legacy_teardrops no)
	)
	(paper "A4")
	(title_block
		(title "Bryce Canyon_F.DPB_16315-1-OCP.brd")
		(comment 1 "Bryce Canyon / footprints 457-460 of 2223")
	)
	(layers
		(0 "F.Cu" signal "TOP")
		(4 "In1.Cu" signal "L2GND")
		(6 "In2.Cu" signal "L3")
		(8 "In3.Cu" signal "L4GND")
		(10 "In4.Cu" signal "L5")
		(12 "In5.Cu" signal "L6VCC")
		(14 "In6.Cu" signal "L7VCC")
		(16 "In7.Cu" signal "L8")
		(18 "In8.Cu" signal "L9GND")
		(20 "In9.Cu" signal "L10")
		(22 "In10.Cu" signal "L11GND")
		(2 "B.Cu" signal "BOTTOM")
		(9 "F.Adhes" user "F.Adhesive")
		(11 "B.Adhes" user "B.Adhesive")
		(13 "F.Paste" user "Package Geometry/Pastemask Top")
		(15 "B.Paste" user "Package Geometry/Pastemask Bottom")
		(5 "F.SilkS" user "Ref Des/Silkscreen Top")
		(7 "B.SilkS" user "Ref Des/Silkscreen Bottom")
		(1 "F.Mask" user "Board Geometry/Soldermask Top")
		(3 "B.Mask" user "Board Geometry/Soldermask Bottom")
		(17 "Dwgs.User" user "User.Drawings")
		(19 "Cmts.User" user "User.Comments")
		(21 "Eco1.User" user "User.Eco1")
		(23 "Eco2.User" user "User.Eco2")
		(25 "Edge.Cuts" user "Board Geometry/Outline")
		(27 "Margin" user)
		(31 "F.CrtYd" user "Package Geometry/Place Bound Top")
		(29 "B.CrtYd" user "Package Geometry/Place Bound Bottom")
		(35 "F.Fab" user "Ref Des/Assembly Top")
		(33 "B.Fab" user "Ref Des/Assembly Bottom")
	)
	(footprint ""
		(layer "F.Cu")
		(at 127.399796 -291.077142 -90)
		(property "Reference" "R201"
			(at 0 0 270)
			(layer "F.SilkS")
			(hide yes)
			(effects
				(font
					(size 1.27 1.27)
				)
			)
		)
		(property "Value" "10KR2F-2-GP"
			(at 0.064008 -3.993896 270)
			(unlocked yes)
			(layer "F.Fab")
			(hide yes)
			(effects
				(font
					(size 1.016 1.016)
					(thickness 0.1524)
				)
			)
		)
		(property "Device Type" "R402H16"
			(at 0.064008 -5.517896 270)
			(unlocked yes)
			(layer "F.Fab")
			(hide yes)
			(effects
				(font
					(size 1.016 1.016)
					(thickness 0.1524)
				)
			)
		)
		(duplicate_pad_numbers_are_jumpers no)
		(fp_line
			(start -0.508 -0.9398)
			(end -0.508 0.9398)
			(stroke
				(width 0.1524)
				(type default)
			)
			(layer "F.SilkS")
		)
		(fp_line
			(start 0.508 -0.9398)
			(end -0.508 -0.9398)
			(stroke
				(width 0.1524)
				(type default)
			)
			(layer "F.SilkS")
		)
		(fp_rect
			(start -0.508 0.9398)
			(end 0.508 -0.9398)
			(stroke
				(width 0)
				(type default)
			)
			(fill no)
			(layer "F.CrtYd")
		)
		(fp_rect
			(start -0.508 0.9398)
			(end 0.508 -0.9398)
			(stroke
				(width 0)
				(type default)
			)
			(fill no)
			(layer "F.Fab")
		)
		(pad "1" smd custom
			(at 0 -0.4445 270)
			(size 0.1397 0.1397)
			(layers "F.Cu" "F.Mask" "F.Paste")
			(net "P3V3_STBY_A")
			(options
				(clearance outline)
				(anchor circle)
			)
			(primitives
				(gr_poly
					(pts
						(arc
							(start -0.1778 -0.2794)
							(mid -0.249642 -0.249642)
							(end -0.2794 -0.1778)
						)
						(arc
							(start -0.2794 0.1778)
							(mid -0.249642 0.249642)
							(end -0.1778 0.2794)
						)
						(arc
							(start 0.1778 0.2794)
							(mid 0.249642 0.249642)
							(end 0.2794 0.1778)
						)
						(arc
							(start 0.2794 -0.1778)
							(mid 0.249642 -0.249642)
							(end 0.1778 -0.2794)
						)
					)
					(width 0)
					(fill yes)
				)
			)
		)
		(pad "2" smd custom
			(at 0 0.4445 270)
			(size 0.1397 0.1397)
			(layers "F.Cu" "F.Mask" "F.Paste")
			(net "HDD_PRSNT_3")
			(options
				(clearance outline)
				(anchor circle)
			)
			(primitives
				(gr_poly
					(pts
						(arc
							(start -0.1778 -0.2794)
							(mid -0.249642 -0.249642)
							(end -0.2794 -0.1778)
						)
						(arc
							(start -0.2794 0.1778)
							(mid -0.249642 0.249642)
							(end -0.1778 0.2794)
						)
						(arc
							(start 0.1778 0.2794)
							(mid 0.249642 0.249642)
							(end 0.2794 0.1778)
						)
						(arc
							(start 0.2794 -0.1778)
							(mid 0.249642 -0.249642)
							(end 0.1778 -0.2794)
						)
					)
					(width 0)
					(fill yes)
				)
			)
		)
	)
	(footprint ""
		(layer "F.Cu")
		(at 144.469866 -131.656074)
		(property "Reference" "C544"
			(at 0 0 0)
			(layer "F.SilkS")
			(hide yes)
			(effects
				(font
					(size 1.27 1.27)
				)
			)
		)
		(property "Value" "SCD1U16V2KX-3GP"
			(at 1.1811 -2.7051 0)
			(unlocked yes)
			(layer "F.Fab")
			(hide yes)
			(effects
				(font
					(size 1.016 1.016)
					(thickness 0.1524)
				)
			)
		)
		(property "Device Type" "C402H22"
			(at 1.1811 -4.2291 0)
			(unlocked yes)
			(layer "F.Fab")
			(hide yes)
			(effects
				(font
					(size 1.016 1.016)
					(thickness 0.1524)
				)
			)
		)
		(duplicate_pad_numbers_are_jumpers no)
		(fp_rect
			(start -0.4318 0.9525)
			(end 0.4318 -0.9525)
			(stroke
				(width 0)
				(type default)
			)
			(fill no)
			(layer "F.CrtYd")
		)
		(fp_rect
			(start -0.4318 0.9525)
			(end 0.4318 -0.9525)
			(stroke
				(width 0)
				(type default)
			)
			(fill no)
			(layer "F.Fab")
		)
		(pad "1" smd custom
			(at 0 -0.4445)
			(size 0.1524 0.1524)
			(layers "F.Cu" "F.Mask" "F.Paste")
			(net "MB0_CM_VOUT_R")
			(options
				(clearance outline)
				(anchor circle)
			)
			(primitives
				(gr_poly
					(pts
						(arc
							(start 0.3048 -0.2032)
							(mid 0.275042 -0.275042)
							(end 0.2032 -0.3048)
						)
						(arc
							(start -0.2032 -0.3048)
							(mid -0.275042 -0.275042)
							(end -0.3048 -0.2032)
						)
						(arc
							(start -0.3048 0.2032)
							(mid -0.275042 0.275042)
							(end -0.2032 0.3048)
						)
						(arc
							(start 0.2032 0.3048)
							(mid 0.275042 0.275042)
							(end 0.3048 0.2032)
						)
					)
					(width 0)
					(fill yes)
				)
			)
		)
		(pad "2" smd custom
			(at 0 0.4445)
			(size 0.1524 0.1524)
			(layers "F.Cu" "F.Mask" "F.Paste")
			(net "AGND_CURRENT_MONOA")
			(options
				(clearance outline)
				(anchor circle)
			)
			(primitives
				(gr_poly
					(pts
						(arc
							(start 0.3048 -0.2032)
							(mid 0.275042 -0.275042)
							(end 0.2032 -0.3048)
						)
						(arc
							(start -0.2032 -0.3048)
							(mid -0.275042 -0.275042)
							(end -0.3048 -0.2032)
						)
						(arc
							(start -0.3048 0.2032)
							(mid -0.275042 0.275042)
							(end -0.2032 0.3048)
						)
						(arc
							(start 0.2032 0.3048)
							(mid 0.275042 0.275042)
							(end 0.3048 0.2032)
						)
					)
					(width 0)
					(fill yes)
				)
			)
		)
	)
	(footprint ""
		(layer "F.Cu")
		(at 388.649972 -57.909968 -90)
		(property "Reference" "HDDSAS32"
			(at 0 0 270)
			(layer "F.SilkS")
			(hide yes)
			(effects
				(font
					(size 1.27 1.27)
				)
			)
		)
		(property "Value" "SKT-SAS15P-14P-45-GP"
			(at -20.7645 -8.9789 270)
			(unlocked yes)
			(layer "F.Fab")
			(hide yes)
			(effects
				(font
					(size 1.016 1.016)
					(thickness 0.1524)
				)
			)
		)
		(property "Device Type" "10120818-001C-TRLF"
			(at -20.7645 -10.5029 270)
			(unlocked yes)
			(layer "F.Fab")
			(hide yes)
			(effects
				(font
					(size 1.016 1.016)
					(thickness 0.1524)
				)
			)
		)
		(duplicate_pad_numbers_are_jumpers no)
		(fp_line
			(start 1.651 4.2926)
			(end 1.651 3.0099)
			(stroke
				(width 0.1524)
				(type default)
			)
			(layer "F.SilkS")
		)
		(fp_line
			(start 8.509 4.2926)
			(end 1.651 4.2926)
			(stroke
				(width 0.1524)
				(type default)
			)
			(layer "F.SilkS")
		)
		(fp_line
			(start -23.4188 3.0099)
			(end -23.4188 -3.2512)
			(stroke
				(width 0.1524)
				(type default)
			)
			(layer "F.SilkS")
		)
		(fp_line
			(start 1.651 3.0099)
			(end -23.4188 3.0099)
			(stroke
				(width 0.1524)
				(type default)
			)
			(layer "F.SilkS")
		)
		(fp_line
			(start 8.509 3.0099)
			(end 8.509 4.2926)
			(stroke
				(width 0.1524)
				(type default)
			)
			(layer "F.SilkS")
		)
		(fp_line
			(start 23.4188 3.0099)
			(end 8.509 3.0099)
			(stroke
				(width 0.1524)
				(type default)
			)
			(layer "F.SilkS")
		)
		(fp_line
			(start -23.4188 -3.2512)
			(end 23.4188 -3.2512)
			(stroke
				(width 0.1524)
				(type default)
			)
			(layer "F.SilkS")
		)
		(fp_line
			(start 23.4188 -3.2512)
			(end 23.4188 3.0099)
			(stroke
				(width 0.1524)
				(type default)
			)
			(layer "F.SilkS")
		)
		(fp_line
			(start 15.5067 -3.3401)
			(end 16.2687 -3.3401)
			(stroke
				(width 0.3302)
				(type default)
			)
			(layer "F.SilkS")
		)
		(fp_poly
			(pts
				(xy 15.868904 -3.230372) (xy 16.503904 -3.865372) (xy 15.233904 -3.865372)
			)
			(stroke
				(width 0)
				(type default)
			)
			(fill yes)
			(layer "F.SilkS")
		)
		(fp_poly
			(pts
				(xy -22.8727 -2.7559) (xy 22.8727 -2.7559) (xy 22.8727 2.7559) (xy 8.255 2.7559) (xy 8.255 3.5179)
				(xy 1.905 3.5179) (xy 1.905 2.7559) (xy -22.8727 2.7559)
			)
			(stroke
				(width 0)
				(type default)
			)
			(fill no)
			(layer "F.CrtYd")
		)
		(fp_poly
			(pts
				(xy 1.397 4.5466) (xy 1.397 3.2639) (xy -23.6728 3.2639) (xy -23.6728 -3.5052) (xy 23.6728 -3.5052)
				(xy 23.6728 -0.00635) (xy 22.8727 -0.00635) (xy 22.8727 -2.7559) (xy -22.8727 -2.7559) (xy -22.8727 2.7559)
				(xy 1.905 2.7559) (xy 1.905 3.5179) (xy 8.255 3.5179) (xy 8.255 2.7559) (xy 22.8727 2.7559) (xy 22.8727 0.00635)
				(xy 23.6728 0.00635) (xy 23.6728 3.2639) (xy 8.763 3.2639) (xy 8.763 4.5466)
			)
			(stroke
				(width 0)
				(type default)
			)
			(fill no)
			(layer "F.CrtYd")
		)
		(fp_poly
			(pts
				(xy 1.397 4.5466) (xy 1.397 3.2639) (xy -23.6728 3.2639) (xy -23.6728 -3.5052) (xy 23.6728 -3.5052)
				(xy 23.6728 3.2639) (xy 8.763 3.2639) (xy 8.763 4.5466)
			)
			(stroke
				(width 0)
				(type default)
			)
			(fill no)
			(layer "F.Fab")
		)
		(pad "" np_thru_hole circle
			(at -18.874994 0 270)
			(size 0.254 0.254)
			(drill 1.3462)
			(layers "*.Cu" "*.Mask")
			(clearance 0.9017)
			(thermal_gap 0.9017)
		)
		(pad "" np_thru_hole circle
			(at 18.874994 0 270)
			(size 0.254 0.254)
			(drill 0.9398)
			(layers "*.Cu" "*.Mask")
			(clearance 0.6985)
			(thermal_gap 0.6985)
		)
		(pad "G1" smd rect
			(at 21.874988 0 270)
			(size 2.5908 2.5908)
			(layers "F.Cu" "F.Mask" "F.Paste")
			(net "GND")
		)
		(pad "G2" smd rect
			(at -21.874988 0 270)
			(size 2.5908 2.5908)
			(layers "F.Cu" "F.Mask" "F.Paste")
			(net "GND")
		)
		(pad "P1" smd rect
			(at 1.905 -1.82499 270)
			(size 0.6096 2.3622)
			(layers "F.Cu" "F.Mask" "F.Paste")
			(net "Net_2046")
		)
		(pad "P2" smd rect
			(at 0.635 -1.82499 270)
			(size 0.6096 2.3622)
			(layers "F.Cu" "F.Mask" "F.Paste")
			(net "Net_2047")
		)
		(pad "P3" smd rect
			(at -0.635 -1.82499 270)
			(size 0.6096 2.3622)
			(layers "F.Cu" "F.Mask" "F.Paste")
			(net "Net_2048")
		)
		(pad "P4" smd rect
			(at -1.905 -1.82499 270)
			(size 0.6096 2.3622)
			(layers "F.Cu" "F.Mask" "F.Paste")
			(net "GND")
		)
		(pad "P5" smd rect
			(at -3.175 -1.82499 270)
			(size 0.6096 2.3622)
			(layers "F.Cu" "F.Mask" "F.Paste")
			(net "HDD_PRSNT_32")
		)
		(pad "P6" smd rect
			(at -4.445 -1.82499 270)
			(size 0.6096 2.3622)
			(layers "F.Cu" "F.Mask" "F.Paste")
			(net "GND")
		)
		(pad "P7" smd rect
			(at -5.715 -1.82499 270)
			(size 0.6096 2.3622)
			(layers "F.Cu" "F.Mask" "F.Paste")
			(net "5V_PRE_32")
		)
		(pad "P8" smd rect
			(at -6.985 -1.82499 270)
			(size 0.6096 2.3622)
			(layers "F.Cu" "F.Mask" "F.Paste")
			(net "P5V_HDD32")
		)
		(pad "P9" smd rect
			(at -8.255 -1.82499 270)
			(size 0.6096 2.3622)
			(layers "F.Cu" "F.Mask" "F.Paste")
			(net "P5V_HDD32")
		)
		(pad "P10" smd rect
			(at -9.525 -1.82499 270)
			(size 0.6096 2.3622)
			(layers "F.Cu" "F.Mask" "F.Paste")
			(net "GND")
		)
		(pad "P11" smd rect
			(at -10.795 -1.82499 270)
			(size 0.6096 2.3622)
			(layers "F.Cu" "F.Mask" "F.Paste")
			(net "ACT_HDD_32")
		)
		(pad "P12" smd rect
			(at -12.065 -1.82499 270)
			(size 0.6096 2.3622)
			(layers "F.Cu" "F.Mask" "F.Paste")
			(net "GND")
		)
		(pad "P13" smd rect
			(at -13.335 -1.82499 270)
			(size 0.6096 2.3622)
			(layers "F.Cu" "F.Mask" "F.Paste")
			(net "12V_PRE_32")
		)
		(pad "P14" smd rect
			(at -14.605 -1.82499 270)
			(size 0.6096 2.3622)
			(layers "F.Cu" "F.Mask" "F.Paste")
			(net "P12V_HDD32")
		)
		(pad "P15" smd rect
			(at -15.875 -1.82499 270)
			(size 0.6096 2.3622)
			(layers "F.Cu" "F.Mask" "F.Paste")
			(net "P12V_HDD32")
		)
		(pad "S1" smd rect
			(at 15.875 -1.82499 270)
			(size 0.6096 2.3622)
			(layers "F.Cu" "F.Mask" "F.Paste")
			(net "GND")
		)
		(pad "S2" smd rect
			(at 14.605 -1.82499 270)
			(size 0.6096 2.3622)
			(layers "F.Cu" "F.Mask" "F.Paste")
			(net "SAS_HDD_RX_P32")
		)
		(pad "S3" smd rect
			(at 13.335 -1.82499 270)
			(size 0.6096 2.3622)
			(layers "F.Cu" "F.Mask" "F.Paste")
			(net "SAS_HDD_RX_N32")
		)
		(pad "S4" smd rect
			(at 12.065 -1.82499 270)
			(size 0.6096 2.3622)
			(layers "F.Cu" "F.Mask" "F.Paste")
			(net "GND")
		)
		(pad "S5" smd rect
			(at 10.795 -1.82499 270)
			(size 0.6096 2.3622)
			(layers "F.Cu" "F.Mask" "F.Paste")
			(net "PHY_DRV_A_TO_SCC_A_32_DN")
		)
		(pad "S6" smd rect
			(at 9.525 -1.82499 270)
			(size 0.6096 2.3622)
			(layers "F.Cu" "F.Mask" "F.Paste")
			(net "PHY_DRV_A_TO_SCC_A_32_DP")
		)
		(pad "S7" smd rect
			(at 8.255 -1.82499 270)
			(size 0.6096 2.3622)
			(layers "F.Cu" "F.Mask" "F.Paste")
			(net "GND")
		)
		(pad "S8" smd rect
			(at 7.480046 2.845054 270)
			(size 0.508 2.3622)
			(layers "F.Cu" "F.Mask" "F.Paste")
			(net "GND")
		)
		(pad "S9" smd rect
			(at 6.679946 2.845054 270)
			(size 0.508 2.3622)
			(layers "F.Cu" "F.Mask" "F.Paste")
			(net "Net_471")
		)
		(pad "S10" smd rect
			(at 5.8801 2.845054 270)
			(size 0.508 2.3622)
			(layers "F.Cu" "F.Mask" "F.Paste")
			(net "Net_363")
		)
		(pad "S11" smd rect
			(at 5.08 2.845054 270)
			(size 0.508 2.3622)
			(layers "F.Cu" "F.Mask" "F.Paste")
			(net "GND")
		)
		(pad "S12" smd rect
			(at 4.2799 2.845054 270)
			(size 0.508 2.3622)
			(layers "F.Cu" "F.Mask" "F.Paste")
			(net "Net_399")
		)
		(pad "S13" smd rect
			(at 3.480054 2.845054 270)
			(size 0.508 2.3622)
			(layers "F.Cu" "F.Mask" "F.Paste")
			(net "Net_435")
		)
		(pad "S14" smd rect
			(at 2.679954 2.845054 270)
			(size 0.508 2.3622)
			(layers "F.Cu" "F.Mask" "F.Paste")
			(net "GND")
		)
		(zone
			(layer "F.Cu")
			(hatch none 0.5)
			(connect_pads
				(clearance 0)
			)
			(min_thickness 0.25)
			(keepout
				(tracks not_allowed)
				(vias allowed)
				(pads allowed)
				(copperpour not_allowed)
				(footprints allowed)
			)
			(placement
				(enabled no)
				(sheetname "")
			)
			(fill
				(thermal_gap 0.5)
				(thermal_bridge_width 0.5)
				(island_removal_mode 0)
			)
			(polygon
				(pts
					(xy 392.307572 -74.648568) (xy 385.233672 -74.648568) (xy 385.233672 -81.582768) (xy 386.338572 -81.582768)
					(xy 386.338572 -77.467968) (xy 390.961372 -77.467968) (xy 390.961372 -81.582768) (xy 392.307572 -81.582768)
				)
			)
		)
		(zone
			(layer "F.Cu")
			(hatch none 0.5)
			(connect_pads
				(clearance 0)
			)
			(min_thickness 0.25)
			(keepout
				(tracks allowed)
				(vias not_allowed)
				(pads allowed)
				(copperpour not_allowed)
				(footprints allowed)
			)
			(placement
				(enabled no)
				(sheetname "")
			)
			(fill
				(thermal_gap 0.5)
				(thermal_bridge_width 0.5)
				(island_removal_mode 0)
			)
			(polygon
				(pts
					(xy 392.307572 -74.648568) (xy 385.233672 -74.648568) (xy 385.233672 -81.582768) (xy 386.338572 -81.582768)
					(xy 386.338572 -77.467968) (xy 390.961372 -77.467968) (xy 390.961372 -81.582768) (xy 392.307572 -81.582768)
				)
			)
		)
		(zone
			(layer "F.Cu")
			(hatch none 0.5)
			(connect_pads
				(clearance 0)
			)
			(min_thickness 0.25)
			(keepout
				(tracks not_allowed)
				(vias allowed)
				(pads allowed)
				(copperpour not_allowed)
				(footprints allowed)
			)
			(placement
				(enabled no)
				(sheetname "")
			)
			(fill
				(thermal_gap 0.5)
				(thermal_bridge_width 0.5)
				(island_removal_mode 0)
			)
			(polygon
				(pts
					(xy 392.307572 -41.171368) (xy 385.233672 -41.171368) (xy 385.233672 -34.237168) (xy 386.338572 -34.237168)
					(xy 386.338572 -38.351968) (xy 390.961372 -38.351968) (xy 390.961372 -34.237168) (xy 392.307572 -34.237168)
				)
			)
		)
		(zone
			(layer "F.Cu")
			(hatch none 0.5)
			(connect_pads
				(clearance 0)
			)
			(min_thickness 0.25)
			(keepout
				(tracks allowed)
				(vias not_allowed)
				(pads allowed)
				(copperpour not_allowed)
				(footprints allowed)
			)
			(placement
				(enabled no)
				(sheetname "")
			)
			(fill
				(thermal_gap 0.5)
				(thermal_bridge_width 0.5)
				(island_removal_mode 0)
			)
			(polygon
				(pts
					(xy 392.307572 -41.171368) (xy 385.233672 -41.171368) (xy 385.233672 -34.237168) (xy 386.338572 -34.237168)
					(xy 386.338572 -38.351968) (xy 390.961372 -38.351968) (xy 390.961372 -34.237168) (xy 392.307572 -34.237168)
				)
			)
		)
		(zone
			(layers "F.Cu" "B.Cu" "In1.Cu" "In2.Cu" "In3.Cu" "In4.Cu" "In5.Cu" "In6.Cu"
				"In7.Cu" "In8.Cu" "In9.Cu" "In10.Cu"
			)
			(hatch none 0.5)
			(connect_pads
				(clearance 0)
			)
			(min_thickness 0.25)
			(keepout
				(tracks not_allowed)
				(vias allowed)
				(pads allowed)
				(copperpour not_allowed)
				(footprints allowed)
			)
			(placement
				(enabled no)
				(sheetname "")
			)
			(fill
				(thermal_gap 0.5)
				(thermal_bridge_width 0.5)
				(island_removal_mode 0)
			)
			(polygon
				(pts
					(arc
						(start 389.424672 -39.034974)
						(mid 387.875272 -39.034974)
						(end 389.424672 -39.034974)
					)
				)
			)
		)
		(zone
			(layers "F.Cu" "B.Cu" "In1.Cu" "In2.Cu" "In3.Cu" "In4.Cu" "In5.Cu" "In6.Cu"
				"In7.Cu" "In8.Cu" "In9.Cu" "In10.Cu"
			)
			(hatch none 0.5)
			(connect_pads
				(clearance 0)
			)
			(min_thickness 0.25)
			(keepout
				(tracks not_allowed)
				(vias allowed)
				(pads allowed)
				(copperpour not_allowed)
				(footprints allowed)
			)
			(placement
				(enabled no)
				(sheetname "")
			)
			(fill
				(thermal_gap 0.5)
				(thermal_bridge_width 0.5)
				(island_removal_mode 0)
			)
			(polygon
				(pts
					(arc
						(start 389.627872 -76.784962)
						(mid 387.672072 -76.784962)
						(end 389.627872 -76.784962)
					)
				)
			)
		)
	)
	(footprint ""
		(layer "F.Cu")
		(at 271.19707 -10.841228 180)
		(property "Reference" "TP200"
			(at 0 0 180)
			(layer "F.SilkS")
			(hide yes)
			(effects
				(font
					(size 1.27 1.27)
				)
			)
		)
		(property "Value" "TPAD32-GP"
			(at -0.0508 -1.6764 180)
			(unlocked yes)
			(layer "F.Fab")
			(hide yes)
			(effects
				(font
					(size 1.016 1.016)
					(thickness 0.1524)
				)
			)
		)
		(property "Device Type" "TPAD32"
			(at -0.0508 -3.2004 180)
			(unlocked yes)
			(layer "F.Fab")
			(hide yes)
			(effects
				(font
					(size 1.016 1.016)
					(thickness 0.1524)
				)
			)
		)
		(duplicate_pad_numbers_are_jumpers no)
		(fp_poly
			(pts
				(arc
					(start -0.4064 0)
					(mid 0.4064 0)
					(end -0.4064 0)
				)
			)
			(stroke
				(width 0)
				(type default)
			)
			(fill no)
			(layer "F.CrtYd")
		)
		(fp_poly
			(pts
				(arc
					(start -0.7112 0)
					(mid 0.7112 0)
					(end -0.7112 0)
				)
			)
			(stroke
				(width 0)
				(type default)
			)
			(fill no)
			(layer "F.Fab")
		)
		(pad "1" smd circle
			(at 0 0 180)
			(size 0.8128 0.8128)
			(layers "F.Cu" "F.Mask" "F.Paste")
			(net "TP_COMP_B_NCSI_RXD1")
		)
	)
)
